# T6G (Grand Teton) — schematic netlist excerpt (pin names and nets, part order shuffled) for the footprints in the layout excerpt that follows; sources: Cadence DE-HDL packaged netlist, KiCad conversion of 04192023_DAF0TMB3IC0_F0TG_MB_C_brd_V02_OCP.brd

R6202  Q_RES  200 1% CHIP  pkg 0402LF  page 176 : A = GND ; B = USB_CPU0_HUB1_RREF_SS
C916  Q_CAP_DIFFBUS  DIFF BUS_0.22UF 6.3V 20% X6S  pkg C0201  page 63 : \1\ = P5E_CPU0_P0_TX_C_DN<8> ; \2\ = P5E_CPU0_P0_TX_DN<8>
R6864  Q_RES  33 5% CHIP  pkg 0402LF  page 151 : A = SMB_HOST_CLK_3V3AUX_SCL_R1 ; B = SMB_9ZXL045_P0_SCL

(kicad_pcb
	(version 20260206)
	(generator "pcbnew")
	(generator_version "10.0")
	(general
		(thickness 1.6)
		(legacy_teardrops no)
	)
	(paper "A4")
	(title_block
		(title "04192023_DAF0TMB3IC0_F0TG_MB_C_brd_V02_OCP.brd")
		(comment 1 "Grand Teton / footprints 2500-2502 of 8354")
	)
	(layers
		(0 "F.Cu" signal "TOP")
		(4 "In1.Cu" signal "GND")
		(6 "In2.Cu" signal "IN1")
		(8 "In3.Cu" signal "GND1")
		(10 "In4.Cu" signal "IN2")
		(12 "In5.Cu" signal "GND2")
		(14 "In6.Cu" signal "IN3")
		(16 "In7.Cu" signal "GND3")
		(18 "In8.Cu" signal "VCC")
		(20 "In9.Cu" signal "VCC1")
		(22 "In10.Cu" signal "GND4")
		(24 "In11.Cu" signal "IN4")
		(26 "In12.Cu" signal "GND5")
		(28 "In13.Cu" signal "IN5")
		(30 "In14.Cu" signal "GND6")
		(32 "In15.Cu" signal "IN6")
		(34 "In16.Cu" signal "GND7")
		(2 "B.Cu" signal "BOTTOM")
		(9 "F.Adhes" user "F.Adhesive")
		(11 "B.Adhes" user "B.Adhesive")
		(13 "F.Paste" user "Package Geometry/Pastemask Top")
		(15 "B.Paste" user "Package Geometry/Pastemask Bottom")
		(5 "F.SilkS" user "Ref Des/Silkscreen Top")
		(7 "B.SilkS" user "Ref Des/Silkscreen Bottom")
		(1 "F.Mask" user "Board Geometry/Soldermask Top")
		(3 "B.Mask" user "Board Geometry/Soldermask Bottom")
		(17 "Dwgs.User" user "User.Drawings")
		(19 "Cmts.User" user "User.Comments")
		(21 "Eco1.User" user "User.Eco1")
		(23 "Eco2.User" user "User.Eco2")
		(25 "Edge.Cuts" user "Board Geometry/Outline")
		(27 "Margin" user)
		(31 "F.CrtYd" user "Package Geometry/Place Bound Top")
		(29 "B.CrtYd" user "Package Geometry/Place Bound Bottom")
		(35 "F.Fab" user "Ref Des/Assembly Top")
		(33 "B.Fab" user "Ref Des/Assembly Bottom")
	)
	(footprint ""
		(layer "F.Cu")
		(at 279.708864 -414.051242)
		(property "Reference" "R6864"
			(at 0 0 0)
			(layer "F.SilkS")
			(hide yes)
			(effects
				(font
					(size 1.27 1.27)
				)
			)
		)
		(property "Value" ""
			(at 0 0 0)
			(layer "F.Fab")
			(effects
				(font
					(size 1.27 1.27)
				)
			)
		)
		(duplicate_pad_numbers_are_jumpers no)
		(fp_line
			(start -0.7874 -0.4064)
			(end 0.7874 -0.4064)
			(stroke
				(width 0.1524)
				(type default)
			)
			(layer "F.SilkS")
		)
		(fp_line
			(start -0.7874 0.4064)
			(end -0.7874 -0.4064)
			(stroke
				(width 0.1524)
				(type default)
			)
			(layer "F.SilkS")
		)
		(fp_line
			(start 0.7874 -0.4064)
			(end 0.7874 0.4064)
			(stroke
				(width 0.1524)
				(type default)
			)
			(layer "F.SilkS")
		)
		(fp_line
			(start 0.7874 0.4064)
			(end -0.7874 0.4064)
			(stroke
				(width 0.1524)
				(type default)
			)
			(layer "F.SilkS")
		)
		(fp_line
			(start -0.67945 -0.305054)
			(end -0.12065 -0.305054)
			(stroke
				(width 0.1)
				(type default)
			)
			(layer "F.Fab")
		)
		(fp_line
			(start -0.67945 0.3048)
			(end -0.67945 -0.305054)
			(stroke
				(width 0.1)
				(type default)
			)
			(layer "F.Fab")
		)
		(fp_line
			(start -0.12065 -0.305054)
			(end -0.12065 -0.2794)
			(stroke
				(width 0.1)
				(type default)
			)
			(layer "F.Fab")
		)
		(fp_line
			(start -0.12065 -0.2794)
			(end 0.12065 -0.2794)
			(stroke
				(width 0.1)
				(type default)
			)
			(layer "F.Fab")
		)
		(fp_line
			(start -0.12065 0.2794)
			(end -0.12065 0.3048)
			(stroke
				(width 0.1)
				(type default)
			)
			(layer "F.Fab")
		)
		(fp_line
			(start -0.12065 0.3048)
			(end -0.67945 0.3048)
			(stroke
				(width 0.1)
				(type default)
			)
			(layer "F.Fab")
		)
		(fp_line
			(start 0.120396 0.2794)
			(end -0.12065 0.2794)
			(stroke
				(width 0.1)
				(type default)
			)
			(layer "F.Fab")
		)
		(fp_line
			(start 0.120396 0.3048)
			(end 0.120396 0.2794)
			(stroke
				(width 0.1)
				(type default)
			)
			(layer "F.Fab")
		)
		(fp_line
			(start 0.12065 -0.3048)
			(end 0.67945 -0.3048)
			(stroke
				(width 0.1)
				(type default)
			)
			(layer "F.Fab")
		)
		(fp_line
			(start 0.12065 -0.2794)
			(end 0.12065 -0.3048)
			(stroke
				(width 0.1)
				(type default)
			)
			(layer "F.Fab")
		)
		(fp_line
			(start 0.67945 -0.3048)
			(end 0.67945 0.3048)
			(stroke
				(width 0.1)
				(type default)
			)
			(layer "F.Fab")
		)
		(fp_line
			(start 0.67945 0.3048)
			(end 0.120396 0.3048)
			(stroke
				(width 0.1)
				(type default)
			)
			(layer "F.Fab")
		)
		(pad "1" smd circle
			(at -0.40005 0)
			(size 0 0)
			(layers "F.Cu" "F.Mask" "F.Paste")
			(net "SMB_HOST_CLK_3V3AUX_SCL_R1")
		)
		(pad "2" smd circle
			(at 0.40005 0)
			(size 0 0)
			(layers "F.Cu" "F.Mask" "F.Paste")
			(net "SMB_9ZXL045_P0_SCL")
		)
	)
	(footprint ""
		(layer "F.Cu")
		(at 126.804928 -48.137064)
		(property "Reference" "R6202"
			(at 0 0 0)
			(layer "F.SilkS")
			(hide yes)
			(effects
				(font
					(size 1.27 1.27)
				)
			)
		)
		(property "Value" ""
			(at 0 0 0)
			(layer "F.Fab")
			(effects
				(font
					(size 1.27 1.27)
				)
			)
		)
		(duplicate_pad_numbers_are_jumpers no)
		(fp_line
			(start -0.7874 -0.4064)
			(end 0.7874 -0.4064)
			(stroke
				(width 0.1524)
				(type default)
			)
			(layer "F.SilkS")
		)
		(fp_line
			(start -0.7874 0.4064)
			(end -0.7874 -0.4064)
			(stroke
				(width 0.1524)
				(type default)
			)
			(layer "F.SilkS")
		)
		(fp_line
			(start 0.7874 -0.4064)
			(end 0.7874 0.4064)
			(stroke
				(width 0.1524)
				(type default)
			)
			(layer "F.SilkS")
		)
		(fp_line
			(start 0.7874 0.4064)
			(end -0.7874 0.4064)
			(stroke
				(width 0.1524)
				(type default)
			)
			(layer "F.SilkS")
		)
		(fp_line
			(start -0.67945 -0.305054)
			(end -0.12065 -0.305054)
			(stroke
				(width 0.1)
				(type default)
			)
			(layer "F.Fab")
		)
		(fp_line
			(start -0.67945 0.3048)
			(end -0.67945 -0.305054)
			(stroke
				(width 0.1)
				(type default)
			)
			(layer "F.Fab")
		)
		(fp_line
			(start -0.12065 -0.305054)
			(end -0.12065 -0.2794)
			(stroke
				(width 0.1)
				(type default)
			)
			(layer "F.Fab")
		)
		(fp_line
			(start -0.12065 -0.2794)
			(end 0.12065 -0.2794)
			(stroke
				(width 0.1)
				(type default)
			)
			(layer "F.Fab")
		)
		(fp_line
			(start -0.12065 0.2794)
			(end -0.12065 0.3048)
			(stroke
				(width 0.1)
				(type default)
			)
			(layer "F.Fab")
		)
		(fp_line
			(start -0.12065 0.3048)
			(end -0.67945 0.3048)
			(stroke
				(width 0.1)
				(type default)
			)
			(layer "F.Fab")
		)
		(fp_line
			(start 0.120396 0.2794)
			(end -0.12065 0.2794)
			(stroke
				(width 0.1)
				(type default)
			)
			(layer "F.Fab")
		)
		(fp_line
			(start 0.120396 0.3048)
			(end 0.120396 0.2794)
			(stroke
				(width 0.1)
				(type default)
			)
			(layer "F.Fab")
		)
		(fp_line
			(start 0.12065 -0.3048)
			(end 0.67945 -0.3048)
			(stroke
				(width 0.1)
				(type default)
			)
			(layer "F.Fab")
		)
		(fp_line
			(start 0.12065 -0.2794)
			(end 0.12065 -0.3048)
			(stroke
				(width 0.1)
				(type default)
			)
			(layer "F.Fab")
		)
		(fp_line
			(start 0.67945 -0.3048)
			(end 0.67945 0.3048)
			(stroke
				(width 0.1)
				(type default)
			)
			(layer "F.Fab")
		)
		(fp_line
			(start 0.67945 0.3048)
			(end 0.120396 0.3048)
			(stroke
				(width 0.1)
				(type default)
			)
			(layer "F.Fab")
		)
		(pad "1" smd circle
			(at -0.40005 0)
			(size 0 0)
			(layers "F.Cu" "F.Mask" "F.Paste")
			(net "GND")
		)
		(pad "2" smd circle
			(at 0.40005 0)
			(size 0 0)
			(layers "F.Cu" "F.Mask" "F.Paste")
			(net "USB_CPU0_HUB1_RREF_SS")
		)
	)
	(footprint ""
		(layer "F.Cu")
		(at 313.518296 -381.41783 -90)
		(property "Reference" "C916"
			(at 0 0 270)
			(layer "F.SilkS")
			(hide yes)
			(effects
				(font
					(size 1.27 1.27)
				)
			)
		)
		(property "Value" ""
			(at 0 0 270)
			(layer "F.Fab")
			(effects
				(font
					(size 1.27 1.27)
				)
			)
		)
		(duplicate_pad_numbers_are_jumpers no)
		(fp_line
			(start -0.299974 0.150114)
			(end -0.299974 -0.150114)
			(stroke
				(width 0.1)
				(type default)
			)
			(layer "F.Fab")
		)
		(fp_line
			(start 0.299974 0.150114)
			(end -0.299974 0.150114)
			(stroke
				(width 0.1)
				(type default)
			)
			(layer "F.Fab")
		)
		(fp_line
			(start -0.299974 -0.150114)
			(end 0.299974 -0.150114)
			(stroke
				(width 0.1)
				(type default)
			)
			(layer "F.Fab")
		)
		(fp_line
			(start 0.299974 -0.150114)
			(end 0.299974 0.150114)
			(stroke
				(width 0.1)
				(type default)
			)
			(layer "F.Fab")
		)
		(pad "1" smd rect
			(at -0.2667 0 270)
			(size 0.3048 0.381)
			(layers "F.Cu" "F.Mask" "F.Paste")
			(net "P5E_CPU0_P0_TX_C_DN<8>")
		)
		(pad "2" smd rect
			(at 0.2667 0 270)
			(size 0.3048 0.381)
			(layers "F.Cu" "F.Mask" "F.Paste")
			(net "P5E_CPU0_P0_TX_DN<8>")
		)
	)
)
